(kicad_pcb
	(version 20260206)
	(generator "pcbnew")
	(generator_version "10.0")
	(general
		(thickness 1.6)
		(legacy_teardrops no)
	)
	(paper "A4")
	(title_block
		(title "peb — Lightning_PEB_BRD.brd")
		(comment 1 "Lightning (Wiwynn / Facebook NVMe JBOF) / footprints 1496-1502 of 2563")
	)
	(layers
		(0 "F.Cu" signal "TOP")
		(4 "In1.Cu" signal "L2GND")
		(6 "In2.Cu" signal "L3")
		(8 "In3.Cu" signal "L4VCC")
		(10 "In4.Cu" signal "L5VCC")
		(12 "In5.Cu" signal "L6")
		(14 "In6.Cu" signal "L7GND")
		(2 "B.Cu" signal "BOTTOM")
		(9 "F.Adhes" user "F.Adhesive")
		(11 "B.Adhes" user "B.Adhesive")
		(13 "F.Paste" user "Package Geometry/Pastemask Top")
		(15 "B.Paste" user "Package Geometry/Pastemask Bottom")
		(5 "F.SilkS" user "Ref Des/Silkscreen Top")
		(7 "B.SilkS" user "Ref Des/Silkscreen Bottom")
		(1 "F.Mask" user "Board Geometry/Soldermask Top")
		(3 "B.Mask" user "Board Geometry/Soldermask Bottom")
		(17 "Dwgs.User" user "User.Drawings")
		(19 "Cmts.User" user "User.Comments")
		(21 "Eco1.User" user "User.Eco1")
		(23 "Eco2.User" user "User.Eco2")
		(25 "Edge.Cuts" user "Board Geometry/Outline")
		(27 "Margin" user)
		(31 "F.CrtYd" user "Package Geometry/Place Bound Top")
		(29 "B.CrtYd" user "Package Geometry/Place Bound Bottom")
		(35 "F.Fab" user "Ref Des/Assembly Top")
		(33 "B.Fab" user "Ref Des/Assembly Bottom")
	)
	(footprint ""
		(layer "F.Cu")
		(at 65.4304 -107.315 -90)
		(property "Reference" "R39"
			(at 0 0 270)
			(layer "F.SilkS")
			(hide yes)
			(effects
				(font
					(size 1.27 1.27)
				)
			)
		)
		(property "Value" "0R2J-2-GP"
			(at 0.064008 -3.993896 270)
			(unlocked yes)
			(layer "F.Fab")
			(hide yes)
			(effects
				(font
					(size 1.016 1.016)
					(thickness 0.1524)
				)
			)
		)
		(property "Device Type" "R402H16"
			(at 0.064008 -5.517896 270)
			(unlocked yes)
			(layer "F.Fab")
			(hide yes)
			(effects
				(font
					(size 1.016 1.016)
					(thickness 0.1524)
				)
			)
		)
		(duplicate_pad_numbers_are_jumpers no)
		(fp_line
			(start -0.508 -0.9398)
			(end -0.508 0.9398)
			(stroke
				(width 0.1524)
				(type default)
			)
			(layer "F.SilkS")
		)
		(fp_line
			(start 0.508 -0.9398)
			(end -0.508 -0.9398)
			(stroke
				(width 0.1524)
				(type default)
			)
			(layer "F.SilkS")
		)
		(fp_rect
			(start -0.508 0.9398)
			(end 0.508 -0.9398)
			(stroke
				(width 0)
				(type default)
			)
			(fill no)
			(layer "F.CrtYd")
		)
		(fp_rect
			(start -0.508 0.9398)
			(end 0.508 -0.9398)
			(stroke
				(width 0)
				(type default)
			)
			(fill no)
			(layer "F.Fab")
		)
		(pad "1" smd custom
			(at 0 -0.4445 270)
			(size 0.1397 0.1397)
			(layers "F.Cu" "F.Mask" "F.Paste")
			(net "BMC_I2C11_MINI5_SCL_S")
			(options
				(clearance outline)
				(anchor circle)
			)
			(primitives
				(gr_poly
					(pts
						(arc
							(start -0.1778 -0.2794)
							(mid -0.249642 -0.249642)
							(end -0.2794 -0.1778)
						)
						(arc
							(start -0.2794 0.1778)
							(mid -0.249642 0.249642)
							(end -0.1778 0.2794)
						)
						(arc
							(start 0.1778 0.2794)
							(mid 0.249642 0.249642)
							(end 0.2794 0.1778)
						)
						(arc
							(start 0.2794 -0.1778)
							(mid 0.249642 -0.249642)
							(end 0.1778 -0.2794)
						)
					)
					(width 0)
					(fill yes)
				)
			)
		)
		(pad "2" smd custom
			(at 0 0.4445 270)
			(size 0.1397 0.1397)
			(layers "F.Cu" "F.Mask" "F.Paste")
			(net "BMC_I2C11_MINI5_SCL")
			(options
				(clearance outline)
				(anchor circle)
			)
			(primitives
				(gr_poly
					(pts
						(arc
							(start -0.1778 -0.2794)
							(mid -0.249642 -0.249642)
							(end -0.2794 -0.1778)
						)
						(arc
							(start -0.2794 0.1778)
							(mid -0.249642 0.249642)
							(end -0.1778 0.2794)
						)
						(arc
							(start 0.1778 0.2794)
							(mid 0.249642 0.249642)
							(end 0.2794 0.1778)
						)
						(arc
							(start 0.2794 -0.1778)
							(mid 0.249642 -0.249642)
							(end 0.1778 -0.2794)
						)
					)
					(width 0)
					(fill yes)
				)
			)
		)
	)
	(footprint ""
		(layer "F.Cu")
		(at 242.6716 -17.9578 180)
		(property "Reference" "R822"
			(at 0 0 180)
			(layer "F.SilkS")
			(hide yes)
			(effects
				(font
					(size 1.27 1.27)
				)
			)
		)
		(property "Value" "4K7R2F-GP"
			(at 0.064008 -3.993896 180)
			(unlocked yes)
			(layer "F.Fab")
			(hide yes)
			(effects
				(font
					(size 1.016 1.016)
					(thickness 0.1524)
				)
			)
		)
		(property "Device Type" "R402H16"
			(at 0.064008 -5.517896 180)
			(unlocked yes)
			(layer "F.Fab")
			(hide yes)
			(effects
				(font
					(size 1.016 1.016)
					(thickness 0.1524)
				)
			)
		)
		(duplicate_pad_numbers_are_jumpers no)
		(fp_line
			(start 0.508 -0.9398)
			(end -0.508 -0.9398)
			(stroke
				(width 0.1524)
				(type default)
			)
			(layer "F.SilkS")
		)
		(fp_line
			(start -0.508 -0.9398)
			(end -0.508 0.9398)
			(stroke
				(width 0.1524)
				(type default)
			)
			(layer "F.SilkS")
		)
		(fp_rect
			(start -0.508 0.9398)
			(end 0.508 -0.9398)
			(stroke
				(width 0)
				(type default)
			)
			(fill no)
			(layer "F.CrtYd")
		)
		(fp_rect
			(start -0.508 0.9398)
			(end 0.508 -0.9398)
			(stroke
				(width 0)
				(type default)
			)
			(fill no)
			(layer "F.Fab")
		)
		(pad "1" smd custom
			(at 0 -0.4445 180)
			(size 0.1397 0.1397)
			(layers "F.Cu" "F.Mask" "F.Paste")
			(net "PM8536_HB")
			(options
				(clearance outline)
				(anchor circle)
			)
			(primitives
				(gr_poly
					(pts
						(arc
							(start -0.1778 -0.2794)
							(mid -0.249642 -0.249642)
							(end -0.2794 -0.1778)
						)
						(arc
							(start -0.2794 0.1778)
							(mid -0.249642 0.249642)
							(end -0.1778 0.2794)
						)
						(arc
							(start 0.1778 0.2794)
							(mid 0.249642 0.249642)
							(end 0.2794 0.1778)
						)
						(arc
							(start 0.2794 -0.1778)
							(mid 0.249642 -0.249642)
							(end 0.1778 -0.2794)
						)
					)
					(width 0)
					(fill yes)
				)
			)
		)
		(pad "2" smd custom
			(at 0 0.4445 180)
			(size 0.1397 0.1397)
			(layers "F.Cu" "F.Mask" "F.Paste")
			(net "P3V3_GPIO")
			(options
				(clearance outline)
				(anchor circle)
			)
			(primitives
				(gr_poly
					(pts
						(arc
							(start -0.1778 -0.2794)
							(mid -0.249642 -0.249642)
							(end -0.2794 -0.1778)
						)
						(arc
							(start -0.2794 0.1778)
							(mid -0.249642 0.249642)
							(end -0.1778 0.2794)
						)
						(arc
							(start 0.1778 0.2794)
							(mid 0.249642 0.249642)
							(end 0.2794 0.1778)
						)
						(arc
							(start 0.2794 -0.1778)
							(mid 0.249642 -0.249642)
							(end 0.1778 -0.2794)
						)
					)
					(width 0)
					(fill yes)
				)
			)
		)
	)
	(footprint ""
		(layer "F.Cu")
		(at 47.244 -182.499 180)
		(property "Reference" "R896"
			(at 0 0 180)
			(layer "F.SilkS")
			(hide yes)
			(effects
				(font
					(size 1.27 1.27)
				)
			)
		)
		(property "Value" "10KR2F-2-GP"
			(at 0.064008 -3.993896 180)
			(unlocked yes)
			(layer "F.Fab")
			(hide yes)
			(effects
				(font
					(size 1.016 1.016)
					(thickness 0.1524)
				)
			)
		)
		(property "Device Type" "R402H16"
			(at 0.064008 -5.517896 180)
			(unlocked yes)
			(layer "F.Fab")
			(hide yes)
			(effects
				(font
					(size 1.016 1.016)
					(thickness 0.1524)
				)
			)
		)
		(duplicate_pad_numbers_are_jumpers no)
		(fp_line
			(start 0.508 -0.9398)
			(end -0.508 -0.9398)
			(stroke
				(width 0.1524)
				(type default)
			)
			(layer "F.SilkS")
		)
		(fp_line
			(start -0.508 -0.9398)
			(end -0.508 0.9398)
			(stroke
				(width 0.1524)
				(type default)
			)
			(layer "F.SilkS")
		)
		(fp_rect
			(start -0.508 0.9398)
			(end 0.508 -0.9398)
			(stroke
				(width 0)
				(type default)
			)
			(fill no)
			(layer "F.CrtYd")
		)
		(fp_rect
			(start -0.508 0.9398)
			(end 0.508 -0.9398)
			(stroke
				(width 0)
				(type default)
			)
			(fill no)
			(layer "F.Fab")
		)
		(pad "1" smd custom
			(at 0 -0.4445 180)
			(size 0.1397 0.1397)
			(layers "F.Cu" "F.Mask" "F.Paste")
			(net "I2C8_BUF_READY")
			(options
				(clearance outline)
				(anchor circle)
			)
			(primitives
				(gr_poly
					(pts
						(arc
							(start -0.1778 -0.2794)
							(mid -0.249642 -0.249642)
							(end -0.2794 -0.1778)
						)
						(arc
							(start -0.2794 0.1778)
							(mid -0.249642 0.249642)
							(end -0.1778 0.2794)
						)
						(arc
							(start 0.1778 0.2794)
							(mid 0.249642 0.249642)
							(end 0.2794 0.1778)
						)
						(arc
							(start 0.2794 -0.1778)
							(mid 0.249642 -0.249642)
							(end 0.1778 -0.2794)
						)
					)
					(width 0)
					(fill yes)
				)
			)
		)
		(pad "2" smd custom
			(at 0 0.4445 180)
			(size 0.1397 0.1397)
			(layers "F.Cu" "F.Mask" "F.Paste")
			(net "P3V3_STBY")
			(options
				(clearance outline)
				(anchor circle)
			)
			(primitives
				(gr_poly
					(pts
						(arc
							(start -0.1778 -0.2794)
							(mid -0.249642 -0.249642)
							(end -0.2794 -0.1778)
						)
						(arc
							(start -0.2794 0.1778)
							(mid -0.249642 0.249642)
							(end -0.1778 0.2794)
						)
						(arc
							(start 0.1778 0.2794)
							(mid 0.249642 0.249642)
							(end 0.2794 0.1778)
						)
						(arc
							(start 0.2794 -0.1778)
							(mid 0.249642 -0.249642)
							(end 0.1778 -0.2794)
						)
					)
					(width 0)
					(fill yes)
				)
			)
		)
	)
	(footprint ""
		(layer "F.Cu")
		(at 13.462 -52.3748 180)
		(property "Reference" "R596"
			(at 0 0 180)
			(layer "F.SilkS")
			(hide yes)
			(effects
				(font
					(size 1.27 1.27)
				)
			)
		)
		(property "Value" "0R2J-2-GP"
			(at 0.064008 -3.993896 180)
			(unlocked yes)
			(layer "F.Fab")
			(hide yes)
			(effects
				(font
					(size 1.016 1.016)
					(thickness 0.1524)
				)
			)
		)
		(property "Device Type" "R402H16"
			(at 0.064008 -5.517896 180)
			(unlocked yes)
			(layer "F.Fab")
			(hide yes)
			(effects
				(font
					(size 1.016 1.016)
					(thickness 0.1524)
				)
			)
		)
		(duplicate_pad_numbers_are_jumpers no)
		(fp_line
			(start 0.508 -0.9398)
			(end -0.508 -0.9398)
			(stroke
				(width 0.1524)
				(type default)
			)
			(layer "F.SilkS")
		)
		(fp_line
			(start -0.508 -0.9398)
			(end -0.508 0.9398)
			(stroke
				(width 0.1524)
				(type default)
			)
			(layer "F.SilkS")
		)
		(fp_rect
			(start -0.508 0.9398)
			(end 0.508 -0.9398)
			(stroke
				(width 0)
				(type default)
			)
			(fill no)
			(layer "F.CrtYd")
		)
		(fp_rect
			(start -0.508 0.9398)
			(end 0.508 -0.9398)
			(stroke
				(width 0)
				(type default)
			)
			(fill no)
			(layer "F.Fab")
		)
		(pad "1" smd custom
			(at 0 -0.4445 180)
			(size 0.1397 0.1397)
			(layers "F.Cu" "F.Mask" "F.Paste")
			(net "NIC0_MDI0_N1_R")
			(options
				(clearance outline)
				(anchor circle)
			)
			(primitives
				(gr_poly
					(pts
						(arc
							(start -0.1778 -0.2794)
							(mid -0.249642 -0.249642)
							(end -0.2794 -0.1778)
						)
						(arc
							(start -0.2794 0.1778)
							(mid -0.249642 0.249642)
							(end -0.1778 0.2794)
						)
						(arc
							(start 0.1778 0.2794)
							(mid 0.249642 0.249642)
							(end 0.2794 0.1778)
						)
						(arc
							(start 0.2794 -0.1778)
							(mid 0.249642 -0.249642)
							(end 0.1778 -0.2794)
						)
					)
					(width 0)
					(fill yes)
				)
			)
		)
		(pad "2" smd custom
			(at 0 0.4445 180)
			(size 0.1397 0.1397)
			(layers "F.Cu" "F.Mask" "F.Paste")
			(net "NIC0_MDI0_N1")
			(options
				(clearance outline)
				(anchor circle)
			)
			(primitives
				(gr_poly
					(pts
						(arc
							(start -0.1778 -0.2794)
							(mid -0.249642 -0.249642)
							(end -0.2794 -0.1778)
						)
						(arc
							(start -0.2794 0.1778)
							(mid -0.249642 0.249642)
							(end -0.1778 0.2794)
						)
						(arc
							(start 0.1778 0.2794)
							(mid 0.249642 0.249642)
							(end 0.2794 0.1778)
						)
						(arc
							(start 0.2794 -0.1778)
							(mid 0.249642 -0.249642)
							(end 0.1778 -0.2794)
						)
					)
					(width 0)
					(fill yes)
				)
			)
		)
	)
	(footprint ""
		(layer "F.Cu")
		(at 78.343506 -82.855054 90)
		(property "Reference" "SC1310"
			(at 0 0 90)
			(layer "F.SilkS")
			(hide yes)
			(effects
				(font
					(size 1.27 1.27)
				)
			)
		)
		(property "Value" "SC10U6D3V5KX-4GP"
			(at -0.0762 -6.1214 90)
			(unlocked yes)
			(layer "F.Fab")
			(hide yes)
			(effects
				(font
					(size 1.016 1.016)
					(thickness 0.1524)
				)
			)
		)
		(property "Device Type" "C805H58"
			(at -0.0762 -8.1534 90)
			(unlocked yes)
			(layer "F.Fab")
			(hide yes)
			(effects
				(font
					(size 1.016 1.016)
					(thickness 0.1524)
				)
			)
		)
		(duplicate_pad_numbers_are_jumpers no)
		(fp_line
			(start 0.635 0)
			(end -0.635 0)
			(stroke
				(width 0.508)
				(type default)
			)
			(layer "F.SilkS")
		)
		(fp_rect
			(start -0.9652 1.778)
			(end 0.9652 -1.778)
			(stroke
				(width 0)
				(type default)
			)
			(fill no)
			(layer "F.CrtYd")
		)
		(fp_poly
			(pts
				(xy -0.9652 -1.778) (xy 0.9652 -1.778) (xy 0.9652 1.778) (xy -0.9652 1.778)
			)
			(stroke
				(width 0)
				(type default)
			)
			(fill no)
			(layer "F.Fab")
		)
		(pad "1" smd rect
			(at 0 -0.9652 90)
			(size 1.397 1.143)
			(layers "F.Cu" "F.Mask" "F.Paste")
			(net "HB_A_IN")
		)
		(pad "2" smd rect
			(at 0 0.9652 90)
			(size 1.397 1.143)
			(layers "F.Cu" "F.Mask" "F.Paste")
			(net "GND")
		)
	)
	(footprint ""
		(layer "F.Cu")
		(at 259.85724 -0.514096 -90)
		(property "Reference" "R7982"
			(at 0 0 270)
			(layer "F.SilkS")
			(hide yes)
			(effects
				(font
					(size 1.27 1.27)
				)
			)
		)
		(property "Value" "0R2J-2-GP"
			(at 0.064008 -3.993896 270)
			(unlocked yes)
			(layer "F.Fab")
			(hide yes)
			(effects
				(font
					(size 1.016 1.016)
					(thickness 0.1524)
				)
			)
		)
		(property "Device Type" "R402H16"
			(at 0.064008 -5.517896 270)
			(unlocked yes)
			(layer "F.Fab")
			(hide yes)
			(effects
				(font
					(size 1.016 1.016)
					(thickness 0.1524)
				)
			)
		)
		(duplicate_pad_numbers_are_jumpers no)
		(fp_line
			(start -0.508 -0.9398)
			(end -0.508 0.9398)
			(stroke
				(width 0.1524)
				(type default)
			)
			(layer "F.SilkS")
		)
		(fp_line
			(start 0.508 -0.9398)
			(end -0.508 -0.9398)
			(stroke
				(width 0.1524)
				(type default)
			)
			(layer "F.SilkS")
		)
		(fp_rect
			(start -0.508 0.9398)
			(end 0.508 -0.9398)
			(stroke
				(width 0)
				(type default)
			)
			(fill no)
			(layer "F.CrtYd")
		)
		(fp_rect
			(start -0.508 0.9398)
			(end 0.508 -0.9398)
			(stroke
				(width 0)
				(type default)
			)
			(fill no)
			(layer "F.Fab")
		)
		(pad "1" smd custom
			(at 0 -0.4445 270)
			(size 0.1397 0.1397)
			(layers "F.Cu" "F.Mask" "F.Paste")
			(net "RST_BTN#")
			(options
				(clearance outline)
				(anchor circle)
			)
			(primitives
				(gr_poly
					(pts
						(arc
							(start -0.1778 -0.2794)
							(mid -0.249642 -0.249642)
							(end -0.2794 -0.1778)
						)
						(arc
							(start -0.2794 0.1778)
							(mid -0.249642 0.249642)
							(end -0.1778 0.2794)
						)
						(arc
							(start 0.1778 0.2794)
							(mid 0.249642 0.249642)
							(end 0.2794 0.1778)
						)
						(arc
							(start 0.2794 -0.1778)
							(mid 0.249642 -0.249642)
							(end 0.1778 -0.2794)
						)
					)
					(width 0)
					(fill yes)
				)
			)
		)
		(pad "2" smd custom
			(at 0 0.4445 270)
			(size 0.1397 0.1397)
			(layers "F.Cu" "F.Mask" "F.Paste")
			(net "DP_RST_N")
			(options
				(clearance outline)
				(anchor circle)
			)
			(primitives
				(gr_poly
					(pts
						(arc
							(start -0.1778 -0.2794)
							(mid -0.249642 -0.249642)
							(end -0.2794 -0.1778)
						)
						(arc
							(start -0.2794 0.1778)
							(mid -0.249642 0.249642)
							(end -0.1778 0.2794)
						)
						(arc
							(start 0.1778 0.2794)
							(mid 0.249642 0.249642)
							(end 0.2794 0.1778)
						)
						(arc
							(start 0.2794 -0.1778)
							(mid 0.249642 -0.249642)
							(end 0.1778 -0.2794)
						)
					)
					(width 0)
					(fill yes)
				)
			)
		)
	)
	(footprint ""
		(layer "F.Cu")
		(at 226.390454 -3.778758)
		(property "Reference" "R176"
			(at 0 0 0)
			(layer "F.SilkS")
			(hide yes)
			(effects
				(font
					(size 1.27 1.27)
				)
			)
		)
		(property "Value" "4K7R2F-GP"
			(at 0.064008 -3.993896 0)
			(unlocked yes)
			(layer "F.Fab")
			(hide yes)
			(effects
				(font
					(size 1.016 1.016)
					(thickness 0.1524)
				)
			)
		)
		(property "Device Type" "R402H16"
			(at 0.064008 -5.517896 0)
			(unlocked yes)
			(layer "F.Fab")
			(hide yes)
			(effects
				(font
					(size 1.016 1.016)
					(thickness 0.1524)
				)
			)
		)
		(duplicate_pad_numbers_are_jumpers no)
		(fp_line
			(start -0.508 -0.9398)
			(end -0.508 0.9398)
			(stroke
				(width 0.1524)
				(type default)
			)
			(layer "F.SilkS")
		)
		(fp_line
			(start 0.508 -0.9398)
			(end -0.508 -0.9398)
			(stroke
				(width 0.1524)
				(type default)
			)
			(layer "F.SilkS")
		)
		(fp_rect
			(start -0.508 0.9398)
			(end 0.508 -0.9398)
			(stroke
				(width 0)
				(type default)
			)
			(fill no)
			(layer "F.CrtYd")
		)
		(fp_rect
			(start -0.508 0.9398)
			(end 0.508 -0.9398)
			(stroke
				(width 0)
				(type default)
			)
			(fill no)
			(layer "F.Fab")
		)
		(pad "1" smd custom
			(at 0 -0.4445)
			(size 0.1397 0.1397)
			(layers "F.Cu" "F.Mask" "F.Paste")
			(net "UART_SWITCH_R")
			(options
				(clearance outline)
				(anchor circle)
			)
			(primitives
				(gr_poly
					(pts
						(arc
							(start -0.1778 -0.2794)
							(mid -0.249642 -0.249642)
							(end -0.2794 -0.1778)
						)
						(arc
							(start -0.2794 0.1778)
							(mid -0.249642 0.249642)
							(end -0.1778 0.2794)
						)
						(arc
							(start 0.1778 0.2794)
							(mid 0.249642 0.249642)
							(end 0.2794 0.1778)
						)
						(arc
							(start 0.2794 -0.1778)
							(mid 0.249642 -0.249642)
							(end 0.1778 -0.2794)
						)
					)
					(width 0)
					(fill yes)
				)
			)
		)
		(pad "2" smd custom
			(at 0 0.4445)
			(size 0.1397 0.1397)
			(layers "F.Cu" "F.Mask" "F.Paste")
			(net "GND")
			(options
				(clearance outline)
				(anchor circle)
			)
			(primitives
				(gr_poly
					(pts
						(arc
							(start -0.1778 -0.2794)
							(mid -0.249642 -0.249642)
							(end -0.2794 -0.1778)
						)
						(arc
							(start -0.2794 0.1778)
							(mid -0.249642 0.249642)
							(end -0.1778 0.2794)
						)
						(arc
							(start 0.1778 0.2794)
							(mid 0.249642 0.249642)
							(end 0.2794 0.1778)
						)
						(arc
							(start 0.2794 -0.1778)
							(mid 0.249642 -0.249642)
							(end 0.1778 -0.2794)
						)
					)
					(width 0)
					(fill yes)
				)
			)
		)
	)
)
